# T6G (Grand Teton) — schematic parts with pin connectivity, parts 4660–4729 of 8303; source: Cadence DE-HDL packaged netlist (pstxprt.dat, pstxnet.dat, pstchip.dat)

Q54  MOSFET_NCH_GDS_ESD_PROTECTED  2N7002K IC  pkg SOT23_GDSXC  page 242
  D  D  BI  = P12V_AUX_BLEEDING
  G  G  IN  = FM_P12V_HSC_EN_R_N
  S  S  BI  = GND

Q56  MOSFET_NCH_1D3S  PSMNR58-30YLH IC  pkg SOT1023  page 188
  1  \1\  BI  = P3V3
  2  \2\  BI  = P3V3
  3  \3\  BI  = P3V3
  4  \4\  IN  = SW_P3V3_EN_ISO_R
  5  \5\  BI  = P3V3_AUX

Q57  MOSFET_NCH_1D3S  PSMNR58-30YLH IC  pkg SOT1023  page 188
  1  \1\  BI  = P5V
  2  \2\  BI  = P5V
  3  \3\  BI  = P5V
  4  \4\  IN  = VR_P5V_EN_D_R
  5  \5\  BI  = P5V_AUX

Q61  MOSFET_N_GSD  NX138BK IC  pkg SOT23_GDSXE  page 164
  D  DRAIN  BI  = UART_LS_EN_R_N
  G  GATE  IN  = UART_LS_EN
  S  SOURCE  BI  = GND

Q62  MOSFET_N  BSS138K IC  pkg SMLF  page 172
  D  DRAIN  OUT  = JTAG_BMC_OE_N
  G  GATE  IN  = JTAG_BMC_OE
  S  SOURCE  BI  = GND

Q63  MOSFET_N  BSS138K IC  pkg SMLF  page 174
  D  DRAIN  OUT  = FM_PLD_CPU0_PRSNT_HDT_N
  G  GATE  IN  = CPU0_HDT_BYPASS_SEL
  S  SOURCE  BI  = GND

Q64  MOSFET_N  BSS138K IC  pkg SMLF  page 174
  D  DRAIN  OUT  = FM_PLD_CPU1_PRSNT_HDT_N
  G  GATE  IN  = CPU1_HDT_BYPASS_SEL
  S  SOURCE  BI  = GND

Q67  MOSFET_NCH_DUAL  PJT138K IC  pkg SOT363XD  page 127
  1  S1  BI  = GND
  2  G1  BI  = BIC_MONITER
  3  D2  BI  = BIC_MONITER_ISO
  4  S2  BI  = GND
  5  G2  BI  = BIC_MONITER_N
  6  D1  BI  = BIC_MONITER_N

Q69  MOSFET_NCH_DUAL  PJT138K IC  pkg SOT363XD  page 127
  1  S1  BI  = GND
  2  G1  BI  = RST_BMC_FROM_SWB_N
  3  D2  BI  = RST_BMC_FROM_SWB_ISO_N
  4  S2  BI  = GND
  5  G2  BI  = RST_BMC_FROM_SWB
  6  D1  BI  = RST_BMC_FROM_SWB

Q70  MOSFET_NCH_DUAL  PJT138K IC  pkg SOT363XD  page 127
  1  S1  BI  = GND
  2  G1  BI  = FM_SWB_BIC_READY_N
  3  D2  BI  = FM_SWB_BIC_READY_ISO_N
  4  S2  BI  = GND
  5  G2  BI  = FM_SWB_BIC_READY
  6  D1  BI  = FM_SWB_BIC_READY

Q71  MOSFET_NCH_DUAL  PJT138K IC  pkg SOT363XD  page 127
  1  S1  BI  = GND
  2  G1  BI  = FM_SWB_PWRGD
  3  D2  BI  = FM_SWB_PWRGD_ISO
  4  S2  BI  = GND
  5  G2  BI  = FM_SWB_PWRGD_N
  6  D1  BI  = FM_SWB_PWRGD_N

Q72  MOSFET_NCH_DUAL  PJT138K IC  pkg SOT363XD  page 127
  1  S1  BI  = GND
  2  G1  BI  = FM_GPU_PWRGD
  3  D2  BI  = FM_GPU_PWRGD_ISO
  4  S2  BI  = GND
  5  G2  BI  = FM_GPU_PWRGD_N
  6  D1  BI  = FM_GPU_PWRGD_N

Q74  MOSFET_NCH_DUAL  PJT138K IC  pkg SOT363XD  page 127
  1  S1  BI  = GND
  2  G1  BI  = FM_SMB_2_ALERT_GPU_N
  3  D2  BI  = FM_SMB_2_ALERT_GPU_ISO_N
  4  S2  BI  = GND
  5  G2  BI  = FM_SMB_2_ALERT_GPU
  6  D1  BI  = FM_SMB_2_ALERT_GPU

Q75  MOSFET_NCH_DUAL  PJT138K IC  pkg SOT363XD  page 127
  1  S1  BI  = GND
  2  G1  BI  = FM_SMB_1_ALERT_GPU_N
  3  D2  BI  = FM_SMB_1_ALERT_GPU_ISO_N
  4  S2  BI  = GND
  5  G2  BI  = FM_SMB_1_ALERT_GPU
  6  D1  BI  = FM_SMB_1_ALERT_GPU

Q78  MOSFET_NCH_DUAL  PJT138K IC  pkg SOT363XD  page 254
  1  S1  BI  = GND
  2  G1  BI  = PWRGD_P1V8_AUX_R
  3  D2  BI  = LED_PWRGD_PS_PWROK_PLD_D
  4  S2  BI  = GND
  5  G2  BI  = PWRGD_PS_PWROK_PLD
  6  D1  BI  = LED_PWRGD_P1V8_AUX_D

Q79  MOSFET_NCH_DUAL  PJT138K IC  pkg SOT363XD  page 255
  1  S1  BI  = GND
  2  G1  BI  = FM_LED_PWRGD_PVDD33_S5
  3  D2  BI  = LED_PWRGD_PVDDCR_CPU0_P0_D
  4  S2  BI  = GND
  5  G2  BI  = FM_LED_PWRGD_PVDDCR_CPU0_P0
  6  D1  BI  = LED_PWRGD_PVDD33_S5_D

Q80  MOSFET_NCH_DUAL  PJT138K IC  pkg SOT363XD  page 255
  1  S1  BI  = GND
  2  G1  BI  = FM_LED_PWRGD_PVDDCR_SOC_P0
  3  D2  BI  = LED_PWRGD_PVDDCR_CPU1_P0_D
  4  S2  BI  = GND
  5  G2  BI  = FM_LED_PWRGD_PVDDCR_CPU1_P0
  6  D1  BI  = LED_PWRGD_PVDDCR_SOC_P0_D

Q81  MOSFET_NCH_DUAL  PJT138K IC  pkg SOT363XD  page 255
  1  S1  BI  = GND
  2  G1  BI  = FM_LED_PWRGD_PVDDIO_P0
  3  D2  BI  = LED_PWRGD_PVDD11_S3_P0_D
  4  S2  BI  = GND
  5  G2  BI  = FM_LED_PWRGD_PVDD11_S3_P0
  6  D1  BI  = LED_PWRGD_PVDDIO_P0_D

Q83  MOSFET_NCH_DUAL  PJT138K IC  pkg SOT363XD  page 255
  1  S1  BI  = GND
  2  G1  BI  = FM_LED_PWRGD_PVDD18_S5_P0
  3  D2  BI  = NC_Q83_D2
  4  S2  BI  = NC_Q83_S2
  5  G2  BI  = NC_Q83_G2
  6  D1  BI  = LED_PWRGD_PVDD18_S5_P0_D

Q84  MOSFET_NCH_DUAL  PJT138K IC  pkg SOT363XD  page 256
  1  S1  BI  = GND
  2  G1  BI  = FM_LED_PWRGD_PVDDCR_CPU0_P1
  3  D2  BI  = LED_PWRGD_PVDDCR_SOC_P1_D
  4  S2  BI  = GND
  5  G2  BI  = FM_LED_PWRGD_PVDDCR_SOC_P1
  6  D1  BI  = LED_PWRGD_PVDDCR_CPU0_P1_D

Q85  MOSFET_NCH_DUAL  PJT138K IC  pkg SOT363XD  page 256
  1  S1  BI  = GND
  2  G1  BI  = FM_LED_PWRGD_PVDDCR_CPU1_P1
  3  D2  BI  = LED_PWRGD_PVDDIO_P1_D
  4  S2  BI  = GND
  5  G2  BI  = FM_LED_PWRGD_PVDDIO_P1
  6  D1  BI  = LED_PWRGD_PVDDCR_CPU1_P1_D

Q86  MOSFET_NCH_DUAL  PJT138K IC  pkg SOT363XD  page 256
  1  S1  BI  = GND
  2  G1  BI  = FM_LED_PWRGD_PVDD11_S3_P1
  3  D2  BI  = LED_PWRGD_PVDD18_S5_P1_D
  4  S2  BI  = GND
  5  G2  BI  = FM_LED_PWRGD_PVDD18_S5_P1
  6  D1  BI  = LED_PWRGD_PVDD11_S3_P1_D

Q87  MOSFET_NCH_DUAL  PJT138K IC  pkg SOT363XD  page 254
  1  S1  BI  = GND
  2  G1  BI  = RST_CPU0_RSMRST_N
  3  D2  BI  = LED_PWRGD_SYS_PWROK_R_D
  4  S2  BI  = GND
  5  G2  BI  = SCM_SYS_PWROK_R2
  6  D1  BI  = LED_RST_RSMRST_PLD_R_N_D

Q95  MOSFET_NCH_DUAL  PJT138K IC  pkg SOT363XD  page 144
  1  S1  BI  = GND
  2  G1  BI  = HDD_ACTIVITY_BUF
  3  D2  BI  = NC_Q95_D2
  4  S2  BI  = NC_Q95_S2
  5  G2  BI  = NC_Q95_G2
  6  D1  BI  = HDD_ACTIVITY_BUF_N

Q96  MOSFET_NCH_DUAL  PJT138K IC  pkg SOT363XD  page 127
  1  S1  BI  = GND
  2  G1  BI  = GPU_FPGA_READY
  3  D2  BI  = GPU_FPGA_READY_ISO
  4  S2  BI  = GND
  5  G2  BI  = GPU_FPGA_READY_N
  6  D1  BI  = GPU_FPGA_READY_N

Q101  MOSFET_NCH_DUAL  PJT138K IC  pkg SOT363XD  page 126
  1  S1  BI  = GND
  2  G1  BI  = GPU_FPGA_THERM_OVERT_N
  3  D2  BI  = GPU_FPGA_THERM_OVERT_ISO_N
  4  S2  BI  = GND
  5  G2  BI  = GPU_FPGA_THERM_OVERT
  6  D1  BI  = GPU_FPGA_THERM_OVERT

Q102  MOSFET_NCH_DUAL  PJT138K IC  pkg SOT363XD  page 126
  1  S1  BI  = GND
  2  G1  BI  = GPU_BASE_HMC_READY
  3  D2  BI  = GPU_BASE_HMC_READY_ISO
  4  S2  BI  = GND
  5  G2  BI  = GPU_BASE_HMC_READY_N
  6  D1  BI  = GPU_BASE_HMC_READY_N

Q103  MOSFET_NCH_DUAL  PJT138K IC  pkg SOT363XD  page 126
  1  S1  BI  = GND
  2  G1  BI  = GPU_HMC_PRSNT_N
  3  D2  BI  = GPU_HMC_PRSNT_ISO_N
  4  S2  BI  = GND
  5  G2  BI  = GPU_HMC_PRSNT
  6  D1  BI  = GPU_HMC_PRSNT

Q104  MOSFET_NCH_DUAL  PJT138K IC  pkg SOT363XD  page 126
  1  S1  BI  = GND
  2  G1  BI  = GPU_FPGA_OVERT_N
  3  D2  BI  = GPU_FPGA_OVERT_ISO_N
  4  S2  BI  = GND
  5  G2  BI  = GPU_FPGA_OVERT
  6  D1  BI  = GPU_FPGA_OVERT

Q106  MOSFET_NCH_DUAL  PJT138K IC  pkg SOT363XD  page 126
  1  S1  BI  = GND
  2  G1  BI  = GPU_WP_HW_CTRL_N
  3  D2  BI  = GPU_WP_HW_CTRL_ISO_N
  4  S2  BI  = GND
  5  G2  BI  = GPU_WP_HW_CTRL_ISO
  6  D1  BI  = GPU_WP_HW_CTRL_ISO

Q107  MOSFET_NCH_DUAL  PJT138K IC  pkg SOT363XD  page 126
  1  S1  BI  = GND
  2  G1  BI  = GPU_PRSNT_N
  3  D2  BI  = GPU_PRSNT_N_ISO
  4  S2  BI  = GND
  5  G2  BI  = GPU_PRSNT
  6  D1  BI  = GPU_PRSNT

Q108  MOSFET_NCH_DUAL  PJT138K IC  pkg SOT363XD  page 126
  1  S1  BI  = GND
  2  G1  BI  = GPU_FPGA_EROT_FATALERR_N
  3  D2  BI  = GPU_FPGA_EROT_FATALERR_ISO_N
  4  S2  BI  = GND
  5  G2  BI  = GPU_FPGA_EROT_FATALERR
  6  D1  BI  = GPU_FPGA_EROT_FATALERR

Q118  MOSFET_NCH_DUAL  PJT138K IC  pkg SOT363XD  page 140
  1  S1  BI  = GND
  2  G1  BI  = P12V_OCP_EN_2_R
  3  D2  BI  = P12V_OCP_UV_2_R
  4  S2  BI  = GND
  5  G2  BI  = P12V_OCP_2_EN_G
  6  D1  BI  = P12V_OCP_2_EN_G

Q119  MOSFET_NCH_DUAL  PJT138K IC  pkg SOT363XD  page 140
  1  S1  BI  = GND
  2  G1  BI  = P3V3_OCP_EN_2_R
  3  D2  BI  = P3V3_OCP_UV_2_R1
  4  S2  BI  = GND
  5  G2  BI  = P3V3_OCP_2_EN_G
  6  D1  BI  = P3V3_OCP_2_EN_G

Q123  MOSFET_NCH_DUAL  PJT138K IC  pkg SOT363XD  page 134
  1  S1  BI  = GND
  2  G1  BI  = P12V_OCP_EN_1_R
  3  D2  BI  = P12V_OCP_UV_1_R
  4  S2  BI  = GND
  5  G2  BI  = P12V_OCP_1_EN_G
  6  D1  BI  = P12V_OCP_1_EN_G

Q124  MOSFET_NCH_DUAL  PJT138K IC  pkg SOT363XD  page 134
  1  S1  BI  = GND
  2  G1  BI  = P3V3_OCP_EN_1_R
  3  D2  BI  = P3V3_OCP_UV_1_R1
  4  S2  BI  = GND
  5  G2  BI  = P3V3_OCP_1_EN_G
  6  D1  BI  = P3V3_OCP_1_EN_G

Q125  MOSFET_NCH_DUAL  PJT138K IC  pkg SOT363XD  page 152
  1  S1  BI  = GND
  2  G1  BI  = P12V_SCM_EN_R
  3  D2  BI  = P12V_SCM_UV_R
  4  S2  BI  = GND
  5  G2  BI  = P12V_SCM_EN_G
  6  D1  BI  = P12V_SCM_EN_G

Q126  MOSFET_NCH_DUAL  PJT138K IC  pkg SOT363XD  page 146
  1  S1  BI  = GND
  2  G1  BI  = P3V3_E1S_EN_0_R
  3  D2  BI  = P3V3_E1S_UV_0_R
  4  S2  BI  = GND
  5  G2  BI  = P3V3_E1S_0_EN_G
  6  D1  BI  = P3V3_E1S_0_EN_G

Q127  MOSFET_NCH_DUAL  PJT138K IC  pkg SOT363XD  page 146
  1  S1  BI  = GND
  2  G1  BI  = P12V_E1S_EN_0_R
  3  D2  BI  = P12V_E1S_UV_0_R
  4  S2  BI  = GND
  5  G2  BI  = P12V_E1S_0_EN_G
  6  D1  BI  = P12V_E1S_0_EN_G

Q128  MOSFET_NCH_DUAL  PJT138K IC  pkg SOT363XD  page 125
  1  S1  BI  = GND
  2  G1  BI  = GPU_3V3IO_RSVD0_FFU
  3  D2  BI  = GPU_3V3IO_RSVD0_FFU_ISO
  4  S2  BI  = GND
  5  G2  BI  = GPU_3V3IO_RSVD0_FFU_N
  6  D1  BI  = GPU_3V3IO_RSVD0_FFU_N

Q129  MOSFET_NCH_DUAL  PJT138K IC  pkg SOT363XD  page 125
  1  S1  BI  = GND
  2  G1  BI  = GPU_3V3IO_RSVD5_FFU
  3  D2  BI  = GPU_3V3IO_RSVD5_FFU_ISO
  4  S2  BI  = GND
  5  G2  BI  = GPU_3V3IO_RSVD5_FFU_N
  6  D1  BI  = GPU_3V3IO_RSVD5_FFU_N

Q130  MOSFET_NCH_DUAL  PJT138K IC  pkg SOT363XD  page 125
  1  S1  BI  = GND
  2  G1  BI  = GPU_3V3IO_RSVD3_FFU
  3  D2  BI  = GPU_3V3IO_RSVD3_FFU_ISO
  4  S2  BI  = GND
  5  G2  BI  = GPU_3V3IO_RSVD3_FFU_N
  6  D1  BI  = GPU_3V3IO_RSVD3_FFU_N

Q131  MOSFET_NCH_DUAL  PJT138K IC  pkg SOT363XD  page 125
  1  S1  BI  = GND
  2  G1  BI  = GPU_3V3IO_RSVD1_FFU
  3  D2  BI  = GPU_3V3IO_RSVD1_FFU_ISO
  4  S2  BI  = GND
  5  G2  BI  = GPU_3V3IO_RSVD1_FFU_N
  6  D1  BI  = GPU_3V3IO_RSVD1_FFU_N

Q132  MOSFET_NCH_DUAL  PJT138K IC  pkg SOT363XD  page 125
  1  S1  BI  = GND
  2  G1  BI  = PRSNT_CABLE_GPU_B3_N
  3  D2  BI  = PRSNT_CABLE_GPU_B3_ISO_N
  4  S2  BI  = GND
  5  G2  BI  = PRSNT_CABLE_GPU_B3
  6  D1  BI  = PRSNT_CABLE_GPU_B3

Q133  MOSFET_NCH_DUAL  PJT138K IC  pkg SOT363XD  page 125
  1  S1  BI  = GND
  2  G1  BI  = PRSNT_CABLE_GPU_A2_N
  3  D2  BI  = PRSNT_CABLE_GPU_A2_ISO_N
  4  S2  BI  = GND
  5  G2  BI  = PRSNT_CABLE_GPU_A2
  6  D1  BI  = PRSNT_CABLE_GPU_A2

Q134  MOSFET_NCH_DUAL  PJT138K IC  pkg SOT363XD  page 125
  1  S1  BI  = GND
  2  G1  BI  = PRSNT_CABLE_GPU_A1_N
  3  D2  BI  = PRSNT_CABLE_GPU_A1_ISO_N
  4  S2  BI  = GND
  5  G2  BI  = PRSNT_CABLE_GPU_A1
  6  D1  BI  = PRSNT_CABLE_GPU_A1

Q135  MOSFET_NCH_DUAL  PJT138K IC  pkg SOT363XD  page 124
  1  S1  BI  = GND
  2  G1  BI  = GPU_3V3IO_RSVD1
  3  D2  BI  = GPU_3V3IO_RSVD1_ISO
  4  S2  BI  = GND
  5  G2  BI  = GPU_3V3IO_RSVD1_N
  6  D1  BI  = GPU_3V3IO_RSVD1_N

Q136  MOSFET_NCH_DUAL  PJT138K IC  pkg SOT363XD  page 124
  1  S1  BI  = GND
  2  G1  BI  = GPU_3V3IO_RSVD4
  3  D2  BI  = GPU_3V3IO_RSVD4_ISO
  4  S2  BI  = GND
  5  G2  BI  = GPU_3V3IO_RSVD4_N
  6  D1  BI  = GPU_3V3IO_RSVD4_N

Q137  MOSFET_NCH_DUAL  PJT138K IC  pkg SOT363XD  page 124
  1  S1  BI  = GND
  2  G1  BI  = GPU_3V3IO_RSVD3
  3  D2  BI  = GPU_3V3IO_RSVD3_ISO
  4  S2  BI  = GND
  5  G2  BI  = GPU_3V3IO_RSVD3_N
  6  D1  BI  = GPU_3V3IO_RSVD3_N

Q144  MOSFET_NCH_DUAL  PJT138K IC  pkg SOT363XD  page 253
  1  S1  BI  = GND
  2  G1  BI  = PWRGD_PS_PWROK_PLD
  3  D2  BI  = PWRGD_PS_PWROK_PLD_ISO
  4  S2  BI  = GND
  5  G2  BI  = PWRGD_PS_PWROK_PLD_N
  6  D1  BI  = PWRGD_PS_PWROK_PLD_N

Q145  MOSFET_NCH_DUAL  PJT138K IC  pkg SOT363XD  page 241
  1  S1  BI  = GND
  2  G1  BI  = HPDB_HSC_PWRGD
  3  D2  BI  = HPDB_HSC_PWRGD_ISO
  4  S2  BI  = GND
  5  G2  BI  = HPDB_HSC_PWRGD_N
  6  D1  BI  = HPDB_HSC_PWRGD_N

Q146  MOSFET_NCH_DUAL  PJT138K IC  pkg SOT363XD  page 125
  1  S1  BI  = GND
  2  G1  BI  = SWB_HSC_PWRGD
  3  D2  BI  = SWB_HSC_PWRGD_ISO
  4  S2  BI  = GND
  5  G2  BI  = SWB_HSC_PWRGD_N
  6  D1  BI  = SWB_HSC_PWRGD_N

Q148  MOSFET_NCH_DUAL  PJT138K IC  pkg SOT363XD  page 124
  1  S1  BI  = GND
  2  G1  BI  = HGX_DETECT_N
  3  D2  BI  = HGX_DETECT_N_ISO
  4  S2  BI  = GND
  5  G2  BI  = HGX_DETECT
  6  D1  BI  = HGX_DETECT

Q6000  MOSFET_NCH_DUAL  PJT138K IC  pkg SOT363XD  page 254
  1  S1  BI  = GND
  2  G1  BI  = PWRGD_P1V2_AUX_R
  6  D1  BI  = LED_PWRGD_P1V2_AUX_D

Q6001  METR3904G  METR3904-G IC  pkg SOT23_BEC  page 267
  B  \1\  IN  = P12V_HSC_TEMP_R
  C  \3\  BI  = P12V_HSC_TEMP_R
  E  \2\  BI  = P12V_HSC_TEMP_E

Q7000  MOSFET_PCH_GDS_ESD_PROTECTED  DMP2035U-7 EMPTY  pkg SOT23_GDSXC  page 169
  D  D  BI  = P12V_AUX_DSC_G2
  G  G  IN  = P12V_AUX_DSC_G1
  S  S  BI  = P12V_AUX_DSC_S1

Q7001  MOSFET_NCH_1D3S  PSMNR58-30YLH EMPTY  pkg SOT1023  page 169
  1  \1\  BI  = GND
  2  \2\  BI  = GND
  3  \3\  BI  = GND
  4  \4\  IN  = P12V_AUX_DSC_G2
  5  \5\  BI  = P12V_AUX_DSC

Q7002  MOSFET_PCH_GDS_ESD_PROTECTED  DMP2035U-7 EMPTY  pkg SOT23_GDSXC  page 169
  D  D  BI  = P3V3_AUX_DSC_G2
  G  G  IN  = P3V3_AUX_DSC_G1
  S  S  BI  = P3V3_AUX_DSC_S1

Q7003  MOSFET_NCH_1D3S  PSMNR58-30YLH EMPTY  pkg SOT1023  page 169
  1  \1\  BI  = GND
  2  \2\  BI  = GND
  3  \3\  BI  = GND
  4  \4\  IN  = P3V3_AUX_DSC_G2
  5  \5\  BI  = P3V3_AUX_DSC

Q8000  MOSFET_NCH_DUAL  PJT138K IC  pkg SOT363XD  page 123
  1  S1  BI  = GND
  2  G1  BI  = PRSNT_SWB_N
  3  D2  BI  = PRSNT_SWB_ISO_N
  4  S2  BI  = GND
  5  G2  BI  = PRSNT_SWB
  6  D1  BI  = PRSNT_SWB

Q8001  MOSFET_NCH_DUAL  PJT138K IC  pkg SOT363XD  page 256
  1  S1  BI  = GND
  2  G1  BI  = P12V_SCM_FAULT_R_N
  3  D2  BI  = LED_P12V_SCM_FAULT_D2
  4  S2  BI  = GND
  5  G2  BI  = LED_P12V_SCM_FAULT_D1
  6  D1  BI  = LED_P12V_SCM_FAULT_D1

Q9000  MOSFET_NCH_DUAL  PJT138K IC  pkg SOT363XD  page 123
  1  S1  BI  = GND
  2  G1  BI  = PRSNT_CABLE_SWB_B1_N
  3  D2  BI  = PRSNT_CABLE_SWB_B1_ISO_N
  4  S2  BI  = GND
  5  G2  BI  = PRSNT_CABLE_SWB_B1
  6  D1  BI  = PRSNT_CABLE_SWB_B1

Q9001  MOSFET_NCH_DUAL  PJT138K IC  pkg SOT363XD  page 123
  1  S1  BI  = GND
  2  G1  BI  = PRSNT_CABLE_SWB_B2_N
  3  D2  BI  = PRSNT_CABLE_SWB_B2_ISO_N
  4  S2  BI  = GND
  5  G2  BI  = PRSNT_CABLE_SWB_B2
  6  D1  BI  = PRSNT_CABLE_SWB_B2

Q9002  MOSFET_NCH_DUAL  PJT138K IC  pkg SOT363XD  page 123
  1  S1  BI  = GND
  2  G1  BI  = PRSNT_CABLE_GPU_A3_N
  3  D2  BI  = PRSNT_CABLE_GPU_A3_ISO_N
  4  S2  BI  = GND
  5  G2  BI  = PRSNT_CABLE_GPU_A3
  6  D1  BI  = PRSNT_CABLE_GPU_A3

Q9003  MOSFET_NCH_DUAL  PJT138K IC  pkg SOT363XD  page 85
  1  S1  BI  = GND
  2  G1  BI  = IRQ_HSC_FAULT_N
  3  D2  BI  = IRQ_HSC_FAULT_BUF_N
  4  S2  BI  = GND
  5  G2  BI  = IRQ_HSC_FAULT
  6  D1  BI  = IRQ_HSC_FAULT

R1  Q_RES  49.9 1% CHIP  pkg 0402LF  page 89 : 1 = I3C_SPD_DDRAF_CPU0_SCL ; 2 = I3C_SPD_DDRD_CPU0_SCL
R2  Q_RES  33.2 1% CHIP  pkg 0402LF  page 85 : 1 = RST_PERST_CPU1_SWB_1_N ; 2 = RST_PERST_CPU1_SWB_1_R_N
R3  Q_RES  2K 1% CHIP  pkg 0402LF  page 83 : 1 = RST_PERST_CPU1_SWB_1_N ; 2 = GND
R4  Q_RES  4.7K 5% EMPTY  pkg 0402LF  page 238 : 1 = P3V3_AUX ; 2 = SMB_CPU_FRU_3V3AUX_SCL
R5  Q_RES  54.9K 1% CHIP  pkg 0402LF  page 90 : 1 = PD_CHE_CPU0_DIMM_SAA ; 2 = GND
